M48
INCH,TZ
T01C.01
T02C.012
T03C.016
T04C.032
T05C.035
T06C.039
T07C.045
T08C.099
T09C.197
T10C.061
T11C.062
T12C.079
T13C.14
T14C.158
T15C.197
;LEADER: 12 
;HEADER: 
;CODE  : ASCII 
;FILE  : 12004-1-1-8.drl for board 12004-1.brd ... layers TOP and BOTTOM
;T01 Holesize 1. = 10.000000 Tolerance = +0.000000/-0.000000 PLATED MILS Quantity = 660
;T02 Holesize 2. = 12.000000 Tolerance = +0.000000/-0.000000 PLATED MILS Quantity = 976
;T03 Holesize 3. = 16.000000 Tolerance = +0.000000/-0.000000 PLATED MILS Quantity = 502
;T04 Holesize 4. = 32.000000 Tolerance = +0.000000/-0.000000 PLATED MILS Quantity = 12
;T05 Holesize 5. = 35.000000 Tolerance = +0.000000/-0.000000 PLATED MILS Quantity = 26
;T06 Holesize 6. = 39.000000 Tolerance = +0.000000/-0.000000 PLATED MILS Quantity = 4
;T07 Holesize 7. = 45.000000 Tolerance = +0.000000/-0.000000 PLATED MILS Quantity = 20
;T08 Holesize 8. = 99.000000 Tolerance = +0.000000/-0.000000 PLATED MILS Quantity = 4
;T09 Holesize 9. = 197.000000 Tolerance = +0.000000/-0.000000 PLATED MILS Quantity = 4
;T10 Holesize 10. = 61.000000 Tolerance = +0.000000/-0.000000 NON_PLATED MILS Quantity = 2
;T11 Holesize 11. = 62.000000 Tolerance = +0.000000/-0.000000 NON_PLATED MILS Quantity = 6
;T12 Holesize 12. = 79.000000 Tolerance = +0.000000/-0.000000 NON_PLATED MILS Quantity = 1
;T13 Holesize 13. = 140.000000 Tolerance = +0.000000/-0.000000 NON_PLATED MILS Quantity = 4
;T14 Holesize 14. = 158.000000 Tolerance = +0.000000/-0.000000 NON_PLATED MILS Quantity = 2
;T15 Holesize 15. = 197.000000 Tolerance = +0.000000/-0.000000 NON_PLATED MILS Quantity = 1
%
G90
T01
X8789Y376072
X6944Y414616
X6750Y425868
X6855Y436844
X7180Y449205
X15872Y441916
X14147Y438989
X17072Y435057
X14206Y433632
X17936Y431103
X13062Y429279
X19015Y426461
X15424Y422722
X11964Y421332
X19757Y418538
X14657Y416838
X14422Y411528
X10615Y411073
X18448Y406788
Y402542
X26551Y394546
X26972Y399588
X23922Y415548
X24357Y423051
X29472Y428016
X23748Y436249
X26611Y441743
X28472Y447107
X37420Y461517
X38566Y451290
X31517Y445328
X36237Y441728
X37988Y438328
X30513Y437850
X30232Y416556
X31808Y410684
X35994Y410146
X32141Y407501
X35738Y406956
X33722Y401639
X43719Y414419
X43659Y432766
X43088Y438073
X46853Y441796
X48298Y454813
X45486Y456341
X42312Y463368
X59063Y485583
X52151Y456887
X52476Y439395
X59209Y438908
X54515Y396433
X53976Y389814
X54463Y386651
X64948Y386626
X64055Y389700
X66931Y398350
X62031Y399713
X66938Y410045
X62439Y413744
X61038Y424878
X67015Y449433
X66903Y457689
X62798Y461555
X66963Y473083
X66991Y476766
X67112Y481066
X59980Y482517
X66931Y484968
X66961Y488885
X69520Y560987
X69555Y564187
X69523Y567387
X68421Y570392
X69450Y573460
X69388Y576660
X69323Y579887
X62681Y589462
X69661Y591387
X66579Y592250
X63125Y592801
X69569Y594959
Y598159
X69599Y601527
X69518Y604727
X69569Y608021
X69496Y611417
X69451Y681103
Y684303
X68928Y687846
X69451Y691003
X69474Y694403
X69316Y697605
X69558Y711913
X69523Y715113
Y718313
X68620Y722610
X69548Y726185
X69472Y729385
X74805Y492842
X78742Y488905
X74870Y488789
X74598Y485021
X70868Y481031
X74805
Y477094
X70868
X74437Y473159
X70868Y473157
X78421Y473078
X70909Y469595
X74702Y469183
X74451Y465323
X79081Y465348
X70488Y465291
X70713Y461504
X79134Y461339
X74460Y461287
X70908Y457771
X74450Y457429
X79050Y457367
X70602Y453533
X74836Y453477
X78754Y453353
Y449904
X70759Y449277
X74695Y449260
X78793Y445704
X74639Y441855
X79094Y441620
X70809Y438057
X74752Y437655
X78798Y433983
X70857Y433857
X74801Y433368
X74780Y429794
X78738Y429679
X70704Y429620
X78811Y426113
X74726Y425594
X78561Y421756
X74656Y421838
X70869Y421840
X70898Y418271
X78939Y414083
X74544Y414071
X70952Y414050
X79016Y410283
X74817Y409752
X70882Y409794
X74869Y406315
X70845Y405839
X70779Y402387
X70775Y398396
X74894Y398251
X78362Y398337
X74702Y394300
X70888Y394222
X74863Y390483
X70865Y390502
X78300Y386505
X77963Y381183
X85721Y385798
X86463Y390483
X86616Y394413
X82663Y398383
X86563Y402383
X82663Y402406
X82555Y406288
X86772Y414047
X82459Y413976
X82763Y417750
X86523Y417943
X86687Y421669
X86505Y425987
X82562Y425980
X86663Y429536
X82681Y430041
X82677Y433595
X86616Y433783
X86493Y441401
X82573Y441360
X82542Y445403
X86568Y445669
X86768Y449383
X82564Y449659
X82732Y453139
X86663Y453583
Y457283
X82663Y457486
X82535Y461227
X86735Y461382
X86765Y465205
X86959Y469276
X82759Y469436
X83021Y473118
X82679Y477094
X86937Y477160
X86616Y488905
X90923Y616187
X91023Y606587
X91343Y598284
X91198Y595087
X91123Y591887
X91223Y588487
X90823Y581387
X91156Y572112
X91852Y563129
X94092Y492819
X94377Y489070
X94490Y484968
X98427
Y481031
X94490
X98626Y477049
X90376Y476918
X90350Y473069
X90359Y469275
X94844Y469182
X98427Y469046
X90965Y465270
X90662Y461604
X98682Y461441
X98597Y457291
X90426Y449431
X94518Y449186
X98433Y449125
X94414Y445605
X98280Y445405
X90426Y441880
X94661Y441681
X98288Y441609
X94490Y437720
X98427
X90480Y437608
X98427Y433783
X94490
X90544Y433408
X98334Y429754
X94490Y429846
X90380Y429650
X90463Y425983
X94369Y425977
X94554Y421911
X90408Y421930
X98363Y421883
X98533Y418180
X94263Y418129
X90563Y417983
X98427Y414098
X90553
Y410161
X98427
X94579Y406324
X94367Y394479
X90566Y394383
X93200Y308800
X106419Y310245
X102555Y394412
X106301Y398350
X102364
Y402287
X106301
X102364Y406224
X106301
X102263Y414083
X106301Y418035
X106210Y421976
X102600Y425983
X106341Y426062
X102364Y429846
X106263Y433683
Y437583
X106363Y441583
X102684Y445671
X106263Y453483
X106149Y457371
X106301Y461346
X106449Y465157
X102469Y469134
X106301Y469220
X102227Y473344
X102364Y477094
X106301Y481031
X102364
Y484968
X106301
X102308Y488978
X110238Y488905
X118004Y488825
X110238Y484968
X114175
Y481031
X110238
Y477094
X114175
Y473157
Y469220
X110263Y469083
Y457283
X110238Y453472
X118238Y453417
X118134Y449362
X118189Y445711
X114175Y445598
X110238
X110263Y441683
X110238Y437720
X114175
X117951Y437592
X114063Y429879
X114091Y425962
X110332Y425814
X110289Y422113
X114175Y418035
X110222Y417989
X114175Y414098
X110238Y410161
X114175
Y406224
Y402287
X110238
X118130Y398511
X114175Y398350
X110238
X110472Y394496
X126184Y310860
X125990Y394413
Y398350
X129927
X122053
X129927Y402287
X125990
X122053
Y406224
X126063Y406183
X125990Y410161
X122053Y414098
X125990
X122053Y418035
X126180Y418224
X122053Y421972
X121943Y425834
X122053Y429846
X125990Y437720
X122053
X129927
X122053Y445598
X125990
X129927
X125897Y453240
X122158Y453388
X122113Y457535
X122053Y465283
X129927
X122053Y469220
X129927
X126057Y469287
X122053Y473157
X129927
X125990Y477094
Y481031
X129927
X122053
X129927Y484968
X122053
X125990
Y488905
X133964Y394555
X133864Y398350
X137801
Y402287
X133864
Y410161
X133863Y413773
Y417883
X138061Y418151
X137570Y421843
X133864Y421972
X133953Y425813
X130081Y425912
X137767Y425993
X133864Y429846
Y433783
X137801Y437720
X133864
X137801Y445598
X133864
X137801Y449535
Y453472
X130080Y457372
X137801Y457409
Y461346
X129963Y461283
X133864Y465283
X137801Y469220
Y473157
Y477094
X133864Y481031
X137801
X133864Y484968
X137801
X133864Y488905
X141738
X149612
X149620Y485149
X141738Y484968
X145675
Y481031
X141738
X149594Y480923
X149612Y477094
X141738
X145675Y473157
Y469220
X149563
X149576Y465497
X145675Y465283
X141827Y461346
X142008Y457429
X149719Y457328
X145567Y453547
X141649Y453189
X145763Y449583
X141738Y449535
X141863Y445583
X145663
X149612Y445598
X145663Y441483
X141763Y437883
X149612Y437720
X145675
X149612Y433783
X145675
X141738Y429846
X145675
X149612
X141775Y426153
X145675Y425909
X149612
X145561Y421879
X141595Y421932
X145737Y418077
X141682Y417902
X145771Y414191
X141738Y414098
X149362Y413951
X141887Y410202
X145795Y410173
X149663Y410083
X149498Y406396
X145765Y406438
X141738Y406224
X145865Y402287
X141738
X149488Y402114
X149583Y398383
X141738Y398350
X145865
X149431Y394402
X141738Y394413
X149783Y390487
X159768Y238444
X157502Y390427
X157574Y394185
X157411Y398513
X157554Y402251
X157698Y406313
X153587Y406496
X153528Y410052
X157251Y414149
X157401Y418143
X153201Y418097
X157463Y421883
X153549Y421972
X157486Y425909
X153549
Y429846
X157486
Y433783
X153549
Y437720
X157486
X153422Y441722
X157560Y445484
X153416Y445539
X153549Y449535
X157411Y449556
X157322Y453385
X153463Y453383
X153646Y457393
X157393Y457572
X153583Y461058
X157486Y461346
X153690Y469111
X157411Y469344
X153549Y473157
X157486
X153549Y477094
X153601Y480894
X157508Y480990
X157486Y484968
X153586Y485118
X157486Y488905
X159589Y817543
X159137Y820712
X157422Y825918
X159688Y829234
Y832484
X158725Y835536
X159431Y838974
X159560Y842172
X154730Y847010
X159426Y848357
X159688Y851564
X160735Y857183
X161423Y492842
X169297
X165360Y488905
X161423Y484968
Y481031
X165353Y480812
X169297Y477094
X161423
X165360
X161423Y473157
X165360
Y469220
X161423
X169297Y465283
X165317Y461561
X161294
X165217Y457361
X161473Y457213
X161455Y453385
X169112Y453260
X165319Y453134
X161423Y449430
X165288Y449306
X169157Y445598
X161423
X165360
X169297Y437720
X161423
X165355Y437582
X161423Y433783
X165355Y433382
X169166Y429679
X165411Y429590
X165363Y425783
X161363Y425780
X161746Y421972
X165360
X161670Y418161
X165621Y418066
X169290Y417960
X165337Y414489
X161277Y414114
X161475Y410299
X165266Y409882
X161499Y402554
X169297Y402536
X165229Y402019
X165455Y398256
X169113Y398299
X161241Y398226
X161477Y394511
X161213Y390551
X169503Y386977
X160004Y233894
X176751Y387090
X178031Y390023
X173425Y390228
X174124Y402624
X179225Y403667
X175463Y413760
X173155Y417978
X176662Y418122
X174351Y429014
X175161Y434723
X173234Y437720
Y453472
X173458Y457178
X173234Y465283
X177182Y467018
X174859Y469220
X175477Y472360
X178053Y474260
X175150Y476294
X176815Y479061
X174601Y481467
X177588Y482616
X174086Y484839
X177763Y486293
X174475Y488016
X178084Y493198
X181414Y490281
X180809Y414170
X181576Y407810
X180991Y398678
X182378Y390377
X203410Y394323
X214660Y362600
X646163Y482677
X646251Y479161
X643296Y477617
X646246Y475961
X646794Y472634
X643914Y470592
X648652Y470028
X650837Y472421
X653351Y470098
X651000Y467700
X658195Y464248
X654990Y463513
X658399Y460842
X659485Y455066
X666818Y452921
X662166Y456914
X661760Y460089
X667831Y479556
X672583Y467901
X671145Y454348
X675745Y448189
X678767Y447136
X682915Y467823
X685815Y496140
X689996Y496274
X698475Y496387
X694169Y496394
X707296Y496348
X702670Y496148
X708059Y449951
X716700Y445400
X713845Y447289
X710645Y447266
X717993Y451389
X719100Y478900
X719700Y485600
X726589Y460909
X729478Y459116
X721445Y455789
X724300Y454000
X721600Y451000
X731780Y452531
X735191Y453967
X735231Y457167
X738636Y457903
X735295Y463720
X731751Y464398
X739751Y469686
X735259Y469898
X738745Y472789
X744986Y481255
X743520Y478297
X746845Y476389
Y473189
X742200Y472500
X749628Y471196
X749974Y477780
T02
X-138100Y222300
X-121100
X-138100Y241300
X-121100
Y260300
X-138100
Y279300
X-121100
Y298300
X-138100
Y317300
X-121100
X-138100Y336300
X-121100
X-104100
X-87100
X-104100Y317300
X-87100
X-104100Y298300
X-87100
Y279300
X-104100
X-87100Y260300
X-104100
Y241300
X-87100
Y222300
X-104100
X-53100
X-70100
Y241300
X-53100
Y260300
X-70100
Y279300
X-49400Y284500
X-70100Y298300
X-53100
Y317300
X-70100
X-53100Y336300
X-70100
X-52600Y356600
Y375600
Y394600
Y413600
X-52500Y432300
Y451300
Y470300
X-53400Y483400
Y502400
X-2400
X-36400
X-19400
X-36400Y483400
X-19400
X-2400
X-1500Y470300
X-35500
X-18500
X-35500Y451300
X-1500
X-18500
X-35500Y432300
X-18500
X-1500
X-1600Y413600
X-35600
X-18600
X-35600Y394600
X-18600
X-1600
X-35600Y375600
X-18600
X-1600
X-18600Y356600
X-35600
X-1600
X-36100Y336300
X-19100
X-2100
X-36100Y317300
X-19100
X-2100
Y298300
X-36100
X-19100
X-1900Y288300
X-19600Y279500
X-36100Y279300
X-2100Y260300
X-19100
X-36300Y260000
X-19100Y241300
X-2100
X-36100
X-19100Y222300
X-2100
X-36100
X39800Y172900
X31500Y185700
X26100Y187300
X27800Y191100
X38800Y194300
X38700Y199700
X29600Y200100
X33400Y266400
X21876Y282289
X39563Y307968
X17100Y311700
X9243Y334400
X29700Y355000
X27284Y358500
X8788Y453864
X20928
X21300Y468000
X29064Y471345
X24315Y472668
X20276Y477090
X20715Y485712
X21090Y497108
X37200Y513500
X32026Y516764
X38200Y528900
X38800Y535700
X73282Y778907
X64000Y765600
X73325Y760926
X67809Y758190
X60122Y747800
X47100Y746000
X69217Y732676
X65447Y711413
X62066Y711051
X65356Y707010
X61193Y706973
X69911Y676938
X73900Y664900
X57500Y662600
X77000Y646200
X72930Y645818
X47000Y645300
X59379Y644787
X67257Y643668
X69220Y614992
X66300Y548000
X67244Y535455
X50893Y534434
X72677Y528615
X73542Y514340
X51383Y514037
X54659Y513125
X63862Y512438
X67140Y511501
X60800Y505200
X56121Y494271
X55295Y479672
X51422Y473540
X47307Y465104
X43345Y386857
X67527Y381818
X43569Y379314
X43639Y374043
X65605Y367307
X61776Y367194
X59316Y300366
X42507Y296616
X59096Y289139
X55420Y288656
X41418Y287473
X59523Y281330
X43181Y278603
X52257Y276649
X70636Y272953
X59523Y271123
X72001Y265901
X55883Y263570
X60102Y263180
X55624Y255132
X60009Y255077
X59258Y246890
X50500Y243100
X60069Y237965
X79189Y235119
X79800Y225900
X76019Y222534
X51600Y217000
X64700Y215100
X43900Y209000
X69400Y207400
X43800Y204800
X49286Y203671
X69000Y202700
X44100Y200600
X73700Y199700
X70200Y199300
X60200Y193550
X74700Y191700
X77200Y189000
X61751Y181464
X69800Y176800
X49500Y169300
X48100Y153800
X76250Y148850
X79900Y148700
X47900Y145500
X70675Y145000
X48100Y133900
X42700Y110500
X63100Y107300
X67300Y107200
X59200Y95573
X77200Y95500
X51800Y93500
X79600Y91500
X51900Y89900
X63400Y89300
X68000Y87750
X43980Y86200
X79500Y85700
X51900Y83600
X82400Y89500
X106300Y105900
X111700Y106100
X117500Y106200
X89000Y107700
X85000Y107800
X85250Y120850
X81150
X89400Y120800
X80207Y139965
X84900Y145300
X85713Y151540
X93303Y154970
X98700Y156200
X107672Y156597
X114700Y157000
X112000Y160700
X103300Y160900
X119900Y162200
X81200Y176000
X107771Y182699
X83800Y188800
X96900Y189286
X80685Y192398
X113815Y194333
X111482Y202800
X84641Y204036
X110610Y206436
X94600Y206900
X94548Y211258
X90813Y225400
X109400
X97885Y228339
X102559Y228575
X113863Y228669
X84863Y229783
X111008Y242830
X87227Y242891
X102713Y242975
X106504Y243329
X100415Y246679
X87698Y246708
X91230Y247047
X108652Y247260
X91819Y250396
X119242Y252107
X94793Y252595
X98211Y252758
X116566Y254205
X106381Y259865
X103003Y260260
X113558Y261260
X87263Y264658
X94051Y265872
X101242Y265901
X90652Y265960
X107887Y266647
X103610Y268626
X114229Y270684
X118219Y274497
X112042Y275903
X107750Y277953
X117027Y278475
X104413Y278608
X95146Y279609
X98546
X119603Y285731
X114915Y290203
X102107Y290439
X98565Y290455
X95202Y290958
X110808Y291075
X105603Y291092
X109534Y314564
X92682Y331571
X117460Y335158
X84200Y380000
X95400Y383083
X84799Y524898
X95599Y525026
X107103Y525057
X118744Y525279
X90878Y585185
X83960Y632636
X83500Y640044
X85600Y647837
X83500Y653600
X85654Y659044
X90174Y678675
X90681Y690157
X93840Y699686
X91130Y701741
X91003Y705214
X90947Y709040
X90746Y712435
X91094Y715818
X91027Y724985
X90814Y734451
X84900Y747900
X85300Y755100
X84703Y758885
X84182Y764879
X84100Y769000
X85000Y775900
X159926Y813000
X151684Y525258
X129199Y525271
X140399Y525238
X128964Y339470
X148102Y338366
X140103Y328216
X121477Y314973
X135613Y308903
X128918Y307533
X152580Y285530
X148834Y284832
X124478Y280855
X142241Y278783
X135308Y276806
X139784Y276432
X121599Y274869
X124874Y273953
X137690Y273752
X152663Y272053
X132163Y271041
X124933Y270414
X152663Y267791
X131901Y267444
X137190Y266587
X134529Y264470
X138228Y260175
X126611Y258265
X130567Y258051
X122572Y258147
X135592Y257933
X132651Y255357
X142933Y251431
X136427Y251413
X151519Y250193
X121685Y249741
X137809Y247647
X121741Y246341
X150666Y243134
X156800Y230500
X154300Y227900
X147013Y225483
X121000Y225300
X125700Y225200
X125600Y221200
X122000Y207300
X122100Y203300
X122400Y199000
X144950Y177338
X158100Y166800
X125300Y162300
X145400Y161955
X122200Y156700
X152350Y131084
X132500Y124600
X197900Y82000
X172200Y128300
X179000
X182400
X175598Y128436
X166700Y128800
X160311Y141680
X170302Y147100
X174339Y151172
X178400Y152300
X199100Y153800
X194800
X188961Y162715
X189600Y166700
X167015Y167633
X189700Y170200
X190018Y173586
X177087Y178920
X172645Y179104
X163550Y179657
X180641Y231683
X175064Y232857
X171200Y233000
X185502Y237383
X196344
X167760Y239626
X196151Y240983
X185740
X167894Y243024
X196021Y244556
X185563Y245456
X168324Y246397
X196078Y248183
X182177Y251208
X182853Y256107
X196365Y256414
X171762Y258345
X192284Y258847
X195698Y259749
X183956Y261452
X183120Y266103
X168010Y267909
X186319Y268076
X183082Y271969
X183043Y276658
X187118Y281963
X183653Y283162
X188273Y285674
X185042Y286734
X172818Y288683
X183707Y289861
X167051Y293752
X183466Y294017
X163142Y294193
X162135Y332650
X184188Y340638
X173508Y348462
X195307Y355649
X197565Y380257
X175767Y380311
X185276Y380362
X189073Y380379
X169600Y380500
X181242Y380481
X177715Y397471
X173864Y397677
X180445Y422567
X174500Y424100
X190887Y424438
X177700Y427300
X181034Y427967
X184750Y427953
X182060Y443776
X196803Y444462
X176915Y446556
X180313Y446694
X195400Y452051
X181980Y458681
X176991Y463723
X195038Y477148
X193016Y496643
X195499Y525203
X184399
X162615Y525220
X173537
X181772Y818429
X181642Y827853
Y837321
X181124Y847013
X181081Y856307
X200798Y846849
X201142Y837191
X201663Y827680
X236973Y795418
X235169Y791455
X228021Y787335
X226949Y782735
X223596Y782163
X237815Y779065
X237950Y774979
X223129Y764830
X228249Y761450
X223671Y740896
X219590Y740816
X236700Y539300
X236300Y535600
X224515Y532633
X237336Y531828
X206699Y525203
X217899Y525103
X219492Y517832
X232912Y507242
X229513Y507141
X226115Y507011
X213500Y503600
X210223Y501477
X216300Y499600
X228500Y498900
X225700Y496800
X231739Y495469
X238118Y492166
X232200Y492100
X228400Y486400
X228001Y474064
X235069Y464940
X211243Y462005
X229600Y460700
X226000Y458700
X237700Y458000
X208632Y457048
X223600Y456200
X203406Y454885
X221035Y453935
X203186Y451492
X202764Y444274
X208947Y443700
X229300Y442500
X239000Y440300
X200453Y439066
X213400Y434601
X201400Y434400
X235600Y433300
X210772Y431456
X220768Y418393
X200161Y416474
X219144Y414536
X206142Y413945
X210042Y412265
X216178Y411331
X237800Y411200
X225421Y410908
X228949Y410741
X233400Y409700
X239600Y405600
X222269Y402278
X226576Y401835
X206871Y397177
X239693Y396029
X217800Y395900
X212500Y395500
X231915Y380533
X228243Y380358
X203379Y380312
X228510Y367624
X238151Y356092
X206775Y348954
X224664Y293860
X222496Y222320
X231350Y222067
X216335Y218212
X238614Y217763
X219717Y211198
X223129Y210901
X231049Y188760
X211700Y181600
X219548Y174651
X223948Y174292
X208200Y153500
X203900
X200100Y150400
Y146500
X212800Y125800
X220100Y123600
X204849Y106438
X201237Y106350
X200100Y101200
X210356Y99104
X212028Y93512
X201614Y89932
X205628Y89404
X210680Y84396
X225231Y58420
X220131Y58163
X235000Y47500
X238700Y47400
X257500Y46900
X266700
X263000Y47000
X253800
X248600Y47200
X244900Y47300
X256928Y69301
X241101Y81230
X261830
X241132Y85023
X254498Y88487
X242488Y88466
X259815Y94233
X251687Y98033
X248000Y114500
X251700Y135484
X246100Y151300
Y155800
Y160400
X255010Y367624
X244928Y367685
X240715Y380333
X264600Y380500
X269840Y386256
X273554Y386722
X257500Y399300
X261300Y402355
X257400Y403206
X264124Y408219
X270800Y408500
X258267Y408800
X275500Y415400
X257184Y421241
X249600Y428100
Y432500
X258299Y432800
X279789Y432846
X260600Y435900
X263000Y438800
X250400Y440000
X279120Y440440
X271342Y440630
X276761Y443421
X277575Y449398
X244800Y454500
X263719Y455536
X259779Y456823
X270714Y458323
X264775Y459236
X255622Y461532
X260322Y462288
X256852Y465331
X253214Y469048
X258221Y469246
X249845Y469508
X246502Y472752
X250400Y473300
X260481Y473769
X269300Y486200
X252200Y486700
X242100Y489000
X248286Y489208
X268215Y490733
X251755Y491731
X246132Y492160
X270700Y495400
X274315Y497133
X268500Y525800
X243300Y527900
X247256Y529218
X268600Y529800
X256300Y531400
X251700Y531500
X243200Y531700
X245800Y534500
X240400
X241300Y539300
X240130Y789012
X271970Y798668
X277254Y852624
X294148Y798547
X282413Y798410
X315696Y798445
X305437Y798205
X281183Y592936
X308800Y540925
X304000Y538500
X283657Y532832
X280259Y532714
X317900Y520100
X314628Y517729
X289405Y515437
X289400Y511700
X304700Y509500
X318015Y493833
X288586Y493703
X305456Y481787
X297715Y479588
X295115Y476433
Y473033
X291300Y468600
X304783Y467192
X290300Y462400
X306603Y459523
X290011Y456234
X289000Y449200
X308900Y449100
X289200Y445100
X309200Y444700
X285565Y438912
X304200Y432600
X300603Y432406
X297238Y429641
X301437Y426833
X304550Y424222
X300059Y422844
X316800Y415900
X314000Y405200
X299800Y398500
X332600Y400100
X341500Y437400
X348800Y437500
X356700
X327900Y438100
X331800Y440400
X331900Y444600
X341430Y459351
X349800Y460000
X353698Y460323
X357812Y460406
X345735Y460843
X323215Y485633
X335532Y485626
X327115Y489533
X330815Y493433
X344815Y494933
X334315Y496733
X321415Y497133
X335600Y511400
X350400Y512000
X343905Y519116
X324400Y570500
X350765Y796385
X346510
X361814Y796557
X382695Y471133
X388884Y468631
X382695Y467033
X387143Y462647
X361533Y460222
X365241Y460010
X391500Y459000
X399900Y458600
X371200Y437800
X363800Y437700
X378700Y437600
X373496Y140021
X365131Y135484
X362793Y126096
X381025Y120650
X362793Y77815
X381025Y73748
X413900Y396400
X428616Y429466
X421273Y439381
X438316Y449493
X438294Y453811
X435138Y460661
X428343Y463067
X420575Y467336
X416588Y467839
X458713Y518034
X469932
X447307Y511890
X465900Y501200
X447090Y497242
X452652Y495705
X471650Y493916
X471410Y490049
X457091Y486699
X471300Y482200
X449000Y480000
X475600Y462100
X450300Y459900
X458900Y446600
X452300Y420900
X473605Y389068
X473838Y385675
X474106Y382285
X506100Y380000
X497279Y382551
X501800Y387600
X517041Y388700
X500526Y394177
X513500Y399060
X500295Y401715
X499764Y411324
X503923Y423910
X508306Y428179
X483100Y449900
X488500Y474200
X501700Y477200
X504500Y479500
X514000Y486293
X498994Y488322
X501802Y490240
X494400Y493600
Y497500
X483008Y500529
X494410Y501344
X482200Y529100
X482183Y535169
X502318Y535328
X484200Y538000
X503300Y539700
X483530Y541762
X483800Y545700
X514073Y552477
X487073Y554094
X512700Y560000
X516900Y561200
X528000Y562900
X521002Y555911
X525300Y552800
X529000Y550500
X523462Y423957
X536736Y418540
X536928Y411324
X523200Y399400
X520900Y388100
X632600Y555200
X636200Y555100
X629100Y536000
X639500Y521900
X638300Y511800
X637200Y393900
X662100Y394600
X667745Y456089
X662604Y463284
X667979Y486293
X674375Y509826
X641700Y510300
X641800Y519000
X658314Y526697
X663600Y535395
X675400Y538100
X672168Y538889
X651800Y540295
X676115Y542633
X671915Y543133
X652400Y545200
X662200Y547300
X643833Y549325
X640100Y550600
X665499Y556600
X644600Y556700
X669200Y559600
X656817Y567131
X643100Y589900
X668987Y731465
X667982Y739870
X663575Y742289
X666516Y784722
X678755Y784815
X669886Y786112
X676727Y790555
X679630Y795856
X646342Y826469
X679332Y841866
X678351Y854383
X718263Y863827
X710727Y862002
X683715Y852233
X681542Y848361
X681156Y844982
X686308Y834802
X690211Y827401
X702290Y820921
X691075Y820814
X684732Y810518
X682693Y806283
X680239Y802378
X711116Y796516
X680480Y773302
X685799Y770894
X700989Y759255
X689945Y758289
X681402Y757754
X707391Y564566
X717879Y564572
X701400Y560200
X697600Y560000
X702400Y554800
Y550600
X694700Y547700
X702000Y546581
X684600Y542100
X712102Y542133
X688800Y540450
X700900Y539500
X705927Y538650
X719866Y528656
X719800Y525000
X709600Y524100
X711900Y521500
X716300Y517125
X707589Y515400
X711400
X700512Y510204
X682015Y493633
X702000Y485700
X688615Y485133
X707700Y476500
X684259Y476130
X707890Y467821
X711409Y467621
X682774Y449737
X693509Y431701
X698300Y431600
X680738Y431633
X684869Y431611
X689111Y431612
X702400Y431500
X722687Y120650
X727300Y273200
X758200Y338900
X756700Y370600
X742000Y505000
X752100Y506500
X756400Y508100
X749500Y508800
X757848Y513543
X755862Y516303
X737297Y517903
X725100Y519600
X756523Y520272
X744073Y522097
X747886
X751965
X723538Y526440
X726800Y527400
X724000Y532600
X752874Y534854
X756272Y534995
X749493Y535216
X722682Y538700
X729600Y540400
X742607Y549481
X746000Y549700
X729700Y551500
X725900Y561800
X758400Y568500
X737400Y576200
X742600Y577100
X727700Y584400
X757600Y639700
X756100Y658700
X746669Y740179
X743653Y744114
X741453Y748054
X738850Y751989
X734450Y755929
X730967Y759864
X724305Y770450
X723678Y774016
X727477Y775212
X724733Y779559
X730028Y782297
X724859Y784497
X729988Y787114
X742663Y788885
X725239Y788970
X729486Y791416
X745230Y793211
X725407Y794540
X739510Y795264
X747659Y796960
X742370Y799077
X744790Y802781
X749593Y803991
X747556Y808994
X749629Y812608
X722443Y826463
X721704Y829981
X724858Y831254
X723801Y834857
X733066Y836450
X726332Y837128
X724093Y840187
X726776Y842277
X729250Y850000
X721243Y850725
X733796Y854172
X721112Y854419
X745100Y859405
X766358Y564600
X762275Y512870
X763000Y490800
X767700Y473300
X768000Y457700
X762900Y387400
T03
X4800Y48600
X5800Y6400
X45900Y50000
X50600Y6000
X50800Y39500
X53200Y26300
X59900Y40600
X65700Y49800
X70700Y45800
X80400Y47800
X87900
X90900Y42400
X96300Y6100
X98700Y48900
X108100Y35300
X108600Y19900
X109700Y6400
X110800Y48800
X119700Y35400
X120200Y48400
X124100Y6700
X126500Y20100
X139800Y31100
X143900Y38000
X146900Y48500
X147200Y7300
X150600Y37800
X153200Y48700
X160500Y19700
X160600Y49100
X167500Y49000
X170400Y31100
X173200Y10900
X185100Y55900
X186000Y35200
X192000Y55900
X197796Y12653
X200700Y51700
Y58300
X208900Y58600
X209100Y51700
X213700Y35200
X224431Y15210
X233900Y32500
X248900Y8400
X252187Y23895
X282282Y47189
X286651Y14571
X286930Y47189
X291373Y47394
X299300Y46400
Y41300
X321300Y37100
Y43200
X325006Y15636
X329900Y37100
X330000Y42800
X351800Y36300
Y42200
X360500Y36700
Y42600
X362775Y20059
X394098
X401343Y58465
X412506Y33484
X432682Y23909
X457399Y46069
X472315Y23056
X496393Y55871
X526213Y34431
X557547Y24335
X573457Y59531
X591122Y33010
X621826Y20111
X657451Y28746
X660180Y56547
X703700Y30300
X721334Y17767
X754800Y56800
Y36800
Y16800
Y76800
X754700Y117600
Y97600
X734333Y88085
X723466Y60810
X692985Y75650
X651658Y95968
X607704Y77545
X555558Y100229
X531425Y77545
X496109Y93412
X457989Y78967
X410025Y87658
X382200Y68500
X382100Y61900
X360200Y68200
Y62300
X352000Y68000
X351900Y62000
X344663Y108965
X329600Y68200
X329500Y62600
X321400Y68500
X321300Y63100
X312275Y98098
X299600Y62100
X299500Y68200
X282444Y106834
X230158Y88359
X230123Y80805
X229870Y73970
X228728Y96613
X228169Y68374
X225851Y73774
X225919Y88394
X225937Y80731
X224285Y96750
X224169Y68520
X221710Y80767
X221722Y88431
X221740Y73844
X209200Y65100
X209000Y72300
X201500
X201200Y65600
X191700Y63300
X191500Y88500
X191000Y71300
X190700Y77800
X184700Y63100
Y88500
X184500Y71200
X183700Y78100
X177500Y77900
X177400Y71400
X177300Y94200
Y88500
X177200Y104800
X177100Y99500
X165200Y79500
X163500Y105500
X163300Y95900
X158000Y79600
X154500Y90000
X151800Y72400
X147500Y90200
X142167Y106366
X142101Y98650
X121700Y75300
X111100Y75500
X100000Y75600
X85300Y70200
X75500Y60800
X70500Y72000
X65500Y60800
X60800Y72500
X55800Y61300
X50500Y67700
X45700Y61000
X5100Y111800
X5000Y71900
Y91900
X4900Y130400
X5000Y150500
X5300Y170000
X57200Y175300
X126700Y173500
X136100Y173800
X165162Y155909
X165388Y160094
X169709Y160049
X169800Y155796
X201900Y130300
X204200Y126700
X206600Y130300
X301140Y161383
X354197Y158187
X451789Y154565
X493200Y145500
X509632Y174434
X545330Y147959
X596334Y173012
X692512Y162589
X754700Y177600
Y157600
Y137600
Y197600
Y217600
Y237600
X699619Y201914
X652714Y200019
X586385Y204283
X521476Y205704
X473097Y208901
X407769Y204757
X390208Y180135
X366982Y198886
X307320Y223390
X258741Y193852
X256823Y221979
X207495Y192761
X136291Y179968
X134600Y222200
X134200Y217300
X130000Y217200
X126300Y180209
X230774Y270268
X241694Y274956
X246169Y246270
X301781Y258122
X322022Y279856
X352066Y262596
X376144Y279856
X384668Y247681
X453252Y250240
X526688Y248818
X602967
X661673Y260892
X688248Y246923
X712386Y297542
X735134Y289819
X754700Y277600
Y257600
X753800Y303200
X766900Y356300
Y333754
X767300Y340400
X767600Y348500
X767100Y418700
X767000Y410900
X766900Y387800
Y364600
Y395400
X766700Y403500
X380956Y408290
X380392Y416962
X376513Y408085
X375949Y416757
X371865Y408085
X371301Y416757
X367217Y407812
X366653Y416484
X232788Y385893
X228635Y385956
X9151Y473051
X16158Y477255
X320207Y428442
X320166Y432442
X366719Y424200
X371367Y424473
X376015
X380458Y424678
X410179Y469769
X410200Y474200
X414894Y453432
X419092Y457572
X419225Y453324
X419296Y449111
X423572Y453454
X432014Y476132
X434412Y479334
X694907Y476993
X694923Y461253
X694851Y469456
X694995Y453626
X711500Y438300
X766500Y435100
X766800Y427000
X767300Y441747
X767400Y465900
X767500Y450800
X767400Y481600
X767200Y489700
Y524500
X766900Y497700
X766800Y535700
X676550Y523677
X672342Y519560
X672257Y523769
X672161Y528021
X668135Y523360
X644900Y538300
X633923Y520400
X566000Y536700
X438300Y481200
X434515Y483333
X264000Y513400
X255500Y514000
X250975Y511729
X245963Y511890
X243100Y516300
X238924Y512390
X234416Y512963
X229764Y513034
X39600Y494800
X38200Y490900
X37329Y524472
X35100Y494400
X33880Y526500
X33921Y520414
X33600Y512600
X18809Y491871
X18064Y513925
X17212Y532250
X8672Y487593
X7927Y509647
X7075Y527972
X196400Y585300
X259600Y568400
X277300Y572500
X309648Y582024
X455846Y546626
X508224Y580873
X587942Y582024
X766700Y592700
X767000Y569500
Y584300
Y576100
X767100Y544600
X767700Y600200
X767100Y623900
Y614800
X766900Y639500
Y631900
X766700Y606900
X740000Y650600
X733000
X726000Y650700
X720000Y650800
X675736Y657222
X614582Y653599
X582620Y653386
X549379Y653173
X375079Y654878
X345034Y658500
X319679Y655730
X289634Y659352
X271949Y648699
X241904Y652321
X179000Y624800
X18277Y641560
X9844Y658803
X8140Y637282
X19981Y663081
X179100Y714600
X193600Y702400
X244248Y682153
X255542Y665532
X272588Y681087
X282176Y713475
X291978Y689184
X302115Y693462
X303272Y672563
X312221Y709853
X320318Y688118
X330758Y707934
X347378Y688332
X358672Y671711
X360803Y704312
X375718Y687266
X388817Y692040
X400222Y683217
X402566Y713049
X413860Y696428
X430267Y679595
X430906Y711983
X445197Y719047
X578784Y682152
X604141Y675547
X607550Y703460
X632693Y697281
X643987Y664041
X650805Y716671
X654641Y691101
X678293Y698772
X694061Y681726
X697897Y662763
X698962Y707936
X715795Y697494
X740513Y687906
X745733Y713048
X750300Y663000
X708231Y730948
X681276Y722211
X628006Y720720
X504632Y761631
X488225Y778464
X474587Y765253
X465851Y758648
X465212Y726260
X448805Y743093
X437511Y759714
X435167Y729882
X420891Y757582
X420252Y725194
X403845Y742027
X395450Y767846
X392551Y758648
X390207Y728816
X378868Y723311
X361442Y736700
X344396Y721145
X333102Y737766
X319171Y767846
X313959Y724732
X312860Y742241
X295814Y726686
X284520Y743307
X202300Y742000
X116188Y771487
X106051Y767209
X48300Y775300
X19768Y758115
X18383Y775694
X9631Y753837
X8246Y771416
X55459Y780063
X112762Y820958
X122899Y825236
X230823Y823850
X419186Y784430
X421530Y814262
X432824Y797641
X449231Y780808
X449870Y813196
X476931Y795085
X486307Y815114
X499945Y828325
X505271Y794019
X516352Y811492
X532332Y836635
X562377Y833013
X764200Y813000
X746266Y873072
X745413Y854763
X729859Y889905
X716221Y876694
X692356Y875629
X675949Y892462
X662311Y879251
X640791Y876268
X624384Y893101
X610746Y879890
X592635Y878186
X576228Y895019
X563016Y865401
X562590Y881808
X545970Y849846
X545118Y880530
X534676Y866467
X528711Y897363
X516991Y843880
X515073Y884152
X510579Y854786
X499208Y899795
X488651Y844946
X463674Y852891
X457542Y893740
X456903Y861352
X440496Y878185
X429202Y894806
X426858Y864974
X397345Y857155
X382963Y895871
X382324Y863483
X365917Y880316
X354623Y896937
X352279Y867105
X332436Y858576
X313925Y896297
X313286Y863909
X296879Y880742
X285585Y897363
X283241Y867531
X254262Y899707
X253623Y867319
X237216Y884152
X223578Y870941
X218729Y857629
X131900Y893200
X120874Y857517
X110737Y853239
X89871Y917500
X131700Y915700
X189273Y902478
X200460Y913771
X213138Y905780
X225922Y900773
X264212Y903112
X337648Y901690
X413927
X517417Y913984
X545757Y912918
X564934Y911640
X593274Y910574
X613090Y909722
X641430Y908656
X664655Y909083
X692995Y908017
X718565Y906526
X746905Y905460
T04
X6614Y553544
X18425
X32204
Y623622
X18425
X10551
X6614Y671654
X18425
X32204
Y741732
X18425
X10551
T05
X22980Y59055
X30854
Y66929
X22980
Y74803
X30854
Y82677
X22980
X30854Y90551
Y98425
X22980Y90551
Y98425
Y106299
X30854
X41142Y135669
Y145669
Y155669
X26181Y517559
Y527559
Y537559
X41142Y635669
Y645669
Y655669
Y753780
Y763780
Y773780
T06
X53547Y302486
Y322486
X182681Y560832
Y580832
T07
X276982Y818335
X286982
X296982
X306982
X316982
X326982
X336982
X346982
X356982
X366982
Y828335
X356982
X346982
X336982
X326982
X316982
X306982
X296982
X286982
X276982
T08
X109410Y796831
X168465
Y876397
X109410
T09
X29528Y19685
X76772
X108268Y905512
X155512
T10
X144843Y812994
Y860234
T11
X54724Y557087
Y620079
Y675197
Y738189
X144843Y798779
Y874449
T12
X-33503Y269685
T13
X-1011811Y-15748
Y940945
X775591Y940944
Y-15748
T14
X-7913Y277559
X-59094
T15
X716535Y39370
M30
